# S9S_MB_2U (Grand Teton) — schematic netlist excerpt (pin names and nets, part order shuffled) for the footprints in the layout excerpt that follows; sources: Cadence DE-HDL packaged netlist, KiCad conversion of 03242023_DA0F0TMBIJ0_F0T_Motherboard_J_brd_V01_OCP.brd

J13  SCONN288_ADR50017P130CC  SCONN288_ADR50017-P130CC IO  pkg DDR288S_1-1VXB  page 94
  VIN_BULK0  = P12V_S3_AUX_CPU0_NVDIMM
  RFU0  = TP_CHG_CPU0_DIMM1_FRU_0
  VIN_MGMT  = P3V3_AUX
  HSCL  = I3C_SPD_DDREFGH_CPU0_LVC1_SCL_4
  HSDA  = I3C_SPD_DDREFGH_CPU0_LVC1_SDA
  VSS0  = GND
  DQ0_A  = M_G_CPU0_SA_DQ<0>
  VSS1  = GND
  DQ1_A  = M_G_CPU0_SA_DQ<1>
  VSS2  = GND
  DQS0_A_T  = M_G_CPU0_SA_DQS_DP<0>
  DQS0_A_C  = M_G_CPU0_SA_DQS_DN<0>
  VSS3  = GND
  DQ4_A  = M_G_CPU0_SA_DQ<4>
  VSS4  = GND
  DQ5_A  = M_G_CPU0_SA_DQ<5>
  VSS5  = GND
  DQ8_A  = M_G_CPU0_SA_DQ<8>
  VSS6  = GND
  DQ9_A  = M_G_CPU0_SA_DQ<9>
  VSS7  = GND
  DQS1_A_T  = M_G_CPU0_SA_DQS_DP<1>
  DQS1_A_C  = M_G_CPU0_SA_DQS_DN<1>
  VSS8  = GND
  DQ12_A  = M_G_CPU0_SA_DQ<12>
  VSS9  = GND
  DQ13_A  = M_G_CPU0_SA_DQ<13>
  VSS10  = GND
  DQ16_A  = M_G_CPU0_SA_DQ<16>
  VSS11  = GND
  DQ17_A  = M_G_CPU0_SA_DQ<17>
  VSS12  = GND
  DQS2_A_T  = M_G_CPU0_SA_DQS_DP<2>
  DQS2_A_C  = M_G_CPU0_SA_DQS_DN<2>
  VSS13  = GND
  DQ20_A  = M_G_CPU0_SA_DQ<20>
  VSS14  = GND
  DQ21_A  = M_G_CPU0_SA_DQ<21>
  VSS15  = GND
  DQ24_A  = M_G_CPU0_SA_DQ<24>
  VSS16  = GND
  DQ25_A  = M_G_CPU0_SA_DQ<25>
  VSS17  = GND
  DQS3_A_T  = M_G_CPU0_SA_DQS_DP<3>
  DQS3_A_C  = M_G_CPU0_SA_DQS_DN<3>
  VSS18  = GND
  DQ28_A  = M_G_CPU0_SA_DQ<28>
  VSS19  = GND
  DQ29_A  = M_G_CPU0_SA_DQ<29>
  VSS20  = GND
  CB0_A  = M_G_CPU0_SA_CB<0>
  VSS21  = GND
  CB1_A  = M_G_CPU0_SA_CB<1>
  VSS22  = GND
  DQS4_A_T  = M_G_CPU0_SA_DQS_DP<4>
  DQS4_A_C  = M_G_CPU0_SA_DQS_DN<4>
  VSS23  = GND
  CB4_A  = M_G_CPU0_SA_CB<4>
  VSS24  = GND
  CB5_A  = M_G_CPU0_SA_CB<5>
  VSS25  = GND
  ALERT_N  = M_G_CPU0_ALERT_N
  VSS26  = GND
  CS0_A_N  = M_G_CPU0_SA_CS_N<0>
  VSS27  = GND
  CA0_A  = M_G_CPU0_SA_CA<0>
  VSS28  = GND
  CA2_A  = M_G_CPU0_SA_CA<2>
  VSS29  = GND
  CA4_A  = M_G_CPU0_SA_CA<4>
  VSS30  = GND
  CA6_A  = M_G_CPU0_SA_CA<6>
  VSS31  = GND
  PAR_A  = M_G_CPU0_SA_PAR
  VSS32  = GND
  CA0_B  = M_G_CPU0_SB_CA<0>
  VSS33  = GND
  CA2_B  = M_G_CPU0_SB_CA<2>
  VSS34  = GND
  CA4_B  = M_G_CPU0_SB_CA<4>
  VSS35  = GND
  CA6_B  = M_G_CPU0_SB_CA<6>
  VSS36  = GND
  CS0_B_N  = M_G_CPU0_SB_CS_N<0>
  VSS37  = GND
  \lbd||rsp_a_n\  = M_G_CPU0_SA_RSP<0>
  \lbs||rsp_b_n\  = M_G_CPU0_SB_RSP<0>
  VSS38  = GND
  CB4_B  = M_G_CPU0_SB_CB<4>
  VSS39  = GND
  CB5_B  = M_G_CPU0_SB_CB<5>
  VSS40  = GND
  \dqs9_b_t||tdqs9_b_t||dbi4_b_n\  = M_G_CPU0_SB_DQS_DP<9>
  \dqs9_b_c||tdqs9_b_c\  = M_G_CPU0_SB_DQS_DN<9>
  VSS41  = GND
  CB0_B  = M_G_CPU0_SB_CB<0>
  VSS42  = GND
  CB1_B  = M_G_CPU0_SB_CB<1>
  VSS43  = GND
  DQ0_B  = M_G_CPU0_SB_DQ<0>
  VSS44  = GND
  DQ1_B  = M_G_CPU0_SB_DQ<1>
  VSS45  = GND
  DQS0_B_T  = M_G_CPU0_SB_DQS_DP<0>
  DQS0_B_C  = M_G_CPU0_SB_DQS_DN<0>
  VSS46  = GND
  DQ4_B  = M_G_CPU0_SB_DQ<4>
  VSS47  = GND
  DQ5_B  = M_G_CPU0_SB_DQ<5>
  VSS48  = GND
  DQ8_B  = M_G_CPU0_SB_DQ<8>
  VSS49  = GND
  DQ9_B  = M_G_CPU0_SB_DQ<9>
  VSS50  = GND
  DQS1_B_T  = M_G_CPU0_SB_DQS_DP<1>
  DQS1_B_C  = M_G_CPU0_SB_DQS_DN<1>
  VSS51  = GND
  DQ12_B  = M_G_CPU0_SB_DQ<12>
  VSS52  = GND
  DQ13_B  = M_G_CPU0_SB_DQ<13>
  VSS53  = GND
  DQ16_B  = M_G_CPU0_SB_DQ<16>
  VSS54  = GND
  DQ17_B  = M_G_CPU0_SB_DQ<17>
  VSS55  = GND
  DQS2_B_T  = M_G_CPU0_SB_DQS_DP<2>
  DQS2_B_C  = M_G_CPU0_SB_DQS_DN<2>
  VSS56  = GND
  DQ20_B  = M_G_CPU0_SB_DQ<20>
  VSS57  = GND
  DQ21_B  = M_G_CPU0_SB_DQ<21>
  VSS58  = GND
  DQ24_B  = M_G_CPU0_SB_DQ<24>
  VSS59  = GND
  DQ25_B  = M_G_CPU0_SB_DQ<25>
  VSS60  = GND
  DQS3_B_T  = M_G_CPU0_SB_DQS_DP<3>
  DQS3_B_C  = M_G_CPU0_SB_DQS_DN<3>
  VSS61  = GND
  DQ28_B  = M_G_CPU0_SB_DQ<28>
  VSS62  = GND
  DQ29_B  = M_G_CPU0_SB_DQ<29>
  VSS63  = GND
  RFU1  = TP_CHG_CPU0_DIMM1_FRU_1
  VIN_BULK1  = P12V_S3_AUX_CPU0_NVDIMM
  VIN_BULK2  = P12V_S3_AUX_CPU0_NVDIMM
  \pwr_good||fail_n\  = PWRGD_CHG_CPU0_DIMM1
  HSA  = PD_CHG_CPU0_DIMM1_SAA
  RFU2  = TP_CHG_CPU0_DIMM1_FRU_2
  RFU3  = TP_CHG_CPU0_DIMM1_FRU_3
  VSS64  = GND
  DQ2_A  = M_G_CPU0_SA_DQ<2>
  VSS65  = GND
  DQ3_A  = M_G_CPU0_SA_DQ<3>
  VSS66  = GND
  \dqs5_a_c||tdqs5_a_c||dqs5_a_t||tdqs5_a_t\  = M_G_CPU0_SA_DQS_DN<5>
  \dqs5_a_t||tdqs5_a_t\  = M_G_CPU0_SA_DQS_DP<5>
  VSS67  = GND
  DQ6_A  = M_G_CPU0_SA_DQ<6>
  VSS68  = GND
  DQ7_A  = M_G_CPU0_SA_DQ<7>
  VSS69  = GND
  DQ10_A  = M_G_CPU0_SA_DQ<10>
  VSS70  = GND
  DQ11_A  = M_G_CPU0_SA_DQ<11>
  VSS71  = GND
  \dqs6_a_c||tdqs6_a_c||dqs6_a_t||tdqs6_a_t\  = M_G_CPU0_SA_DQS_DN<6>
  \dqs6_a_t||tdqs6_a_t\  = M_G_CPU0_SA_DQS_DP<6>
  VSS72  = GND
  DQ14_A  = M_G_CPU0_SA_DQ<14>
  VSS73  = GND
  DQ15_A  = M_G_CPU0_SA_DQ<15>
  VSS74  = GND
  DQ18_A  = M_G_CPU0_SA_DQ<18>
  VSS75  = GND
  DQ19_A  = M_G_CPU0_SA_DQ<19>
  VSS76  = GND
  \dqs7_a_c||tdqs7_a_c\  = M_G_CPU0_SA_DQS_DN<7>
  \dqs7_a_t||tdqs7_a_t\  = M_G_CPU0_SA_DQS_DP<7>
  VSS77  = GND
  DQ22_A  = M_G_CPU0_SA_DQ<22>
  VSS78  = GND
  DQ23_A  = M_G_CPU0_SA_DQ<23>
  VSS79  = GND
  DQ26_A  = M_G_CPU0_SA_DQ<26>
  VSS80  = GND
  DQ27_A  = M_G_CPU0_SA_DQ<27>
  VSS81  = GND
  \dqs8_a_c||tdqs8_a_c\  = M_G_CPU0_SA_DQS_DN<8>
  \dqs8_a_t||tdqs8_a_t\  = M_G_CPU0_SA_DQS_DP<8>
  VSS82  = GND
  DQ30_A  = M_G_CPU0_SA_DQ<30>
  VSS83  = GND
  DQ31_A  = M_G_CPU0_SA_DQ<31>
  VSS84  = GND
  CB2_A  = M_G_CPU0_SA_CB<2>
  VSS85  = GND
  CB3_A  = M_G_CPU0_SA_CB<3>
  VSS86  = GND
  \dqs9_a_c||tdqs9_a_c\  = M_G_CPU0_SA_DQS_DN<9>
  \dqs9_a_t||tdqs9_a_t\  = M_G_CPU0_SA_DQS_DP<9>
  VSS87  = GND
  CB6_A  = M_G_CPU0_SA_CB<6>
  VSS88  = GND
  CB7_A  = M_G_CPU0_SA_CB<7>
  VSS89  = GND
  RESET_N  = RST_M_GH_CPU0_FPGA_N
  VSS90  = GND
  CS1_A_N  = M_G_CPU0_SA_CS_N<1>
  VSS91  = GND
  CA1_A  = M_G_CPU0_SA_CA<1>
  VSS92  = GND
  CA3_A  = M_G_CPU0_SA_CA<3>
  VSS93  = GND
  CA5_A  = M_G_CPU0_SA_CA<5>
  VSS94  = GND
  CK_T  = M_G_CPU0_CLK_DP<0>
  CK_C  = M_G_CPU0_CLK_DN<0>
  VSS95  = GND
  RFU4  = TP_CHG_CPU0_DIMM1_FRU_4
  CA1_B  = M_G_CPU0_SB_CA<1>
  VSS96  = GND
  CA3_B  = M_G_CPU0_SB_CA<3>
  VSS97  = GND
  CA5_B  = M_G_CPU0_SB_CA<5>
  VSS98  = GND
  PAR_B  = M_G_CPU0_SB_PAR
  VSS99  = GND
  CS1_B_N  = M_G_CPU0_SB_CS_N<1>
  VSS100  = GND
  RFU5  = TP_CHG_CPU0_DIMM1_FRU_5
  RFU6  = TP_CHG_CPU0_DIMM1_FRU_6
  VSS101  = GND
  CB6_B  = M_G_CPU0_SB_CB<6>
  VSS102  = GND
  CB7_B  = M_G_CPU0_SB_CB<7>
  VSS103  = GND
  DQS4_B_C  = M_G_CPU0_SB_DQS_DN<4>
  DQS4_B_T  = M_G_CPU0_SB_DQS_DP<4>
  VSS104  = GND
  CB2_B  = M_G_CPU0_SB_CB<2>
  VSS105  = GND
  CB3_B  = M_G_CPU0_SB_CB<3>
  VSS106  = GND
  DQ2_B  = M_G_CPU0_SB_DQ<2>
  VSS107  = GND
  DQ3_B  = M_G_CPU0_SB_DQ<3>
  VSS108  = GND
  \dqs5_b_c||tdqs5_b_c\  = M_G_CPU0_SB_DQS_DN<5>
  \dqs5_b_t||tdqs5_b_t\  = M_G_CPU0_SB_DQS_DP<5>
  VSS109  = GND
  DQ6_B  = M_G_CPU0_SB_DQ<6>
  VSS110  = GND
  DQ7_B  = M_G_CPU0_SB_DQ<7>
  VSS111  = GND
  DQ10_B  = M_G_CPU0_SB_DQ<10>
  VSS112  = GND
  DQ11_B  = M_G_CPU0_SB_DQ<11>
  VSS113  = GND
  \dqs6_b_c||tdqs6_b_c\  = M_G_CPU0_SB_DQS_DN<6>
  \dqs6_b_t||tdqs6_b_t\  = M_G_CPU0_SB_DQS_DP<6>
  VSS114  = GND
  DQ14_B  = M_G_CPU0_SB_DQ<14>
  VSS115  = GND
  DQ15_B  = M_G_CPU0_SB_DQ<15>
  VSS116  = GND
  DQ18_B  = M_G_CPU0_SB_DQ<18>
  VSS117  = GND
  DQ19_B  = M_G_CPU0_SB_DQ<19>
  VSS118  = GND
  \dqs7_b_c||tdqs7_b_c\  = M_G_CPU0_SB_DQS_DN<7>
  \dqs7_b_t||tdqs7_b_t\  = M_G_CPU0_SB_DQS_DP<7>
  VSS119  = GND
  DQ22_B  = M_G_CPU0_SB_DQ<22>
  VSS120  = GND
  DQ23_B  = M_G_CPU0_SB_DQ<23>
  VSS121  = GND
  DQ26_B  = M_G_CPU0_SB_DQ<26>
  VSS122  = GND
  DQ27_B  = M_G_CPU0_SB_DQ<27>
  VSS123  = GND
  \dqs8_b_c||tdqs8_b_c\  = M_G_CPU0_SB_DQS_DN<8>
  \dqs8_b_t||tdqs8_b_t\  = M_G_CPU0_SB_DQS_DP<8>
  VSS124  = GND
  DQ30_B  = M_G_CPU0_SB_DQ<30>
  VSS125  = GND
  DQ31_B  = M_G_CPU0_SB_DQ<31>
  VSS126  = GND
  G1  = GND
  G2  = GND
  G3  = GND

(kicad_pcb
	(version 20260206)
	(generator "pcbnew")
	(generator_version "10.0")
	(general
		(thickness 1.6)
		(legacy_teardrops no)
	)
	(paper "A4")
	(title_block
		(title "03242023_DA0F0TMBIJ0_F0T_Motherboard_J_brd_V01_OCP.brd")
		(comment 1 "Grand Teton / footprint 1368 of 6105 (J13), pads 229-274 of 291")
	)
	(layers
		(0 "F.Cu" signal "TOP")
		(4 "In1.Cu" signal "GND")
		(6 "In2.Cu" signal "IN1")
		(8 "In3.Cu" signal "GND1")
		(10 "In4.Cu" signal "IN2")
		(12 "In5.Cu" signal "GND2")
		(14 "In6.Cu" signal "IN3")
		(16 "In7.Cu" signal "GND3")
		(18 "In8.Cu" signal "VCC")
		(20 "In9.Cu" signal "VCC1")
		(22 "In10.Cu" signal "GND4")
		(24 "In11.Cu" signal "IN4")
		(26 "In12.Cu" signal "GND5")
		(28 "In13.Cu" signal "IN5")
		(30 "In14.Cu" signal "GND6")
		(32 "In15.Cu" signal "IN6")
		(34 "In16.Cu" signal "GND7")
		(2 "B.Cu" signal "BOTTOM")
		(9 "F.Adhes" user "F.Adhesive")
		(11 "B.Adhes" user "B.Adhesive")
		(13 "F.Paste" user "Package Geometry/Pastemask Top")
		(15 "B.Paste" user "Package Geometry/Pastemask Bottom")
		(5 "F.SilkS" user "Ref Des/Silkscreen Top")
		(7 "B.SilkS" user "Ref Des/Silkscreen Bottom")
		(1 "F.Mask" user "Board Geometry/Soldermask Top")
		(3 "B.Mask" user "Board Geometry/Soldermask Bottom")
		(17 "Dwgs.User" user "User.Drawings")
		(19 "Cmts.User" user "User.Comments")
		(21 "Eco1.User" user "User.Eco1")
		(23 "Eco2.User" user "User.Eco2")
		(25 "Edge.Cuts" user "Board Geometry/Outline")
		(27 "Margin" user)
		(31 "F.CrtYd" user "Package Geometry/Place Bound Top")
		(29 "B.CrtYd" user "Package Geometry/Place Bound Bottom")
		(35 "F.Fab" user "Ref Des/Assembly Top")
		(33 "B.Fab" user "Ref Des/Assembly Bottom")
	)
	(footprint ""
		(layer "F.Cu")
		(at 446.522348 -258.091686)
		(property "Reference" "J13"
			(at -3.683 -81.702148 0)
			(unlocked yes)
			(layer "F.SilkS")
			(effects
				(font
					(size 0.7874 0.5842)
					(thickness 0.1524)
				)
				(justify left)
			)
		)
		(property "Value" ""
			(at 0 0 0)
			(layer "F.Fab")
			(effects
				(font
					(size 1.27 1.27)
				)
			)
		)
		(duplicate_pad_numbers_are_jumpers no)
		(pad "229" smd rect
			(at 2.050034 13.17498 270)
			(size 0.519938 1.4986)
			(layers "F.Cu" "F.Mask" "F.Paste")
			(net "M_G_CPU0_SB_CS_N<1>")
		)
		(pad "230" smd rect
			(at 2.050034 14.025118 270)
			(size 0.519938 1.4986)
			(layers "F.Cu" "F.Mask" "F.Paste")
			(net "GND")
		)
		(pad "231" smd rect
			(at 2.050034 14.875002 270)
			(size 0.519938 1.4986)
			(layers "F.Cu" "F.Mask" "F.Paste")
			(net "TP_CHG_CPU0_DIMM1_FRU_5")
		)
		(pad "232" smd rect
			(at 2.050034 15.724886 270)
			(size 0.519938 1.4986)
			(layers "F.Cu" "F.Mask" "F.Paste")
			(net "TP_CHG_CPU0_DIMM1_FRU_6")
		)
		(pad "233" smd rect
			(at 2.050034 16.575024 270)
			(size 0.519938 1.4986)
			(layers "F.Cu" "F.Mask" "F.Paste")
			(net "GND")
		)
		(pad "234" smd rect
			(at 2.050034 17.424908 270)
			(size 0.519938 1.4986)
			(layers "F.Cu" "F.Mask" "F.Paste")
			(net "M_G_CPU0_SB_CB<6>")
		)
		(pad "235" smd rect
			(at 2.050034 18.275046 270)
			(size 0.519938 1.4986)
			(layers "F.Cu" "F.Mask" "F.Paste")
			(net "GND")
		)
		(pad "236" smd rect
			(at 2.050034 19.12493 270)
			(size 0.519938 1.4986)
			(layers "F.Cu" "F.Mask" "F.Paste")
			(net "M_G_CPU0_SB_CB<7>")
		)
		(pad "237" smd rect
			(at 2.050034 19.975068 270)
			(size 0.519938 1.4986)
			(layers "F.Cu" "F.Mask" "F.Paste")
			(net "GND")
		)
		(pad "238" smd rect
			(at 2.050034 20.824952 270)
			(size 0.519938 1.4986)
			(layers "F.Cu" "F.Mask" "F.Paste")
			(net "M_G_CPU0_SB_DQS_DN<4>")
		)
		(pad "239" smd rect
			(at 2.050034 21.67509 270)
			(size 0.519938 1.4986)
			(layers "F.Cu" "F.Mask" "F.Paste")
			(net "M_G_CPU0_SB_DQS_DP<4>")
		)
		(pad "240" smd rect
			(at 2.050034 22.524974 270)
			(size 0.519938 1.4986)
			(layers "F.Cu" "F.Mask" "F.Paste")
			(net "GND")
		)
		(pad "241" smd rect
			(at 2.050034 23.375112 270)
			(size 0.519938 1.4986)
			(layers "F.Cu" "F.Mask" "F.Paste")
			(net "M_G_CPU0_SB_CB<2>")
		)
		(pad "242" smd rect
			(at 2.050034 24.224996 270)
			(size 0.519938 1.4986)
			(layers "F.Cu" "F.Mask" "F.Paste")
			(net "GND")
		)
		(pad "243" smd rect
			(at 2.050034 25.07488 270)
			(size 0.519938 1.4986)
			(layers "F.Cu" "F.Mask" "F.Paste")
			(net "M_G_CPU0_SB_CB<3>")
		)
		(pad "244" smd rect
			(at 2.050034 25.925018 270)
			(size 0.519938 1.4986)
			(layers "F.Cu" "F.Mask" "F.Paste")
			(net "GND")
		)
		(pad "245" smd rect
			(at 2.050034 26.774902 270)
			(size 0.519938 1.4986)
			(layers "F.Cu" "F.Mask" "F.Paste")
			(net "M_G_CPU0_SB_DQ<2>")
		)
		(pad "246" smd rect
			(at 2.050034 27.62504 270)
			(size 0.519938 1.4986)
			(layers "F.Cu" "F.Mask" "F.Paste")
			(net "GND")
		)
		(pad "247" smd rect
			(at 2.050034 28.474924 270)
			(size 0.519938 1.4986)
			(layers "F.Cu" "F.Mask" "F.Paste")
			(net "M_G_CPU0_SB_DQ<3>")
		)
		(pad "248" smd rect
			(at 2.050034 29.325062 270)
			(size 0.519938 1.4986)
			(layers "F.Cu" "F.Mask" "F.Paste")
			(net "GND")
		)
		(pad "249" smd rect
			(at 2.050034 30.174946 270)
			(size 0.519938 1.4986)
			(layers "F.Cu" "F.Mask" "F.Paste")
			(net "M_G_CPU0_SB_DQS_DN<5>")
		)
		(pad "250" smd rect
			(at 2.050034 31.025084 270)
			(size 0.519938 1.4986)
			(layers "F.Cu" "F.Mask" "F.Paste")
			(net "M_G_CPU0_SB_DQS_DP<5>")
		)
		(pad "251" smd rect
			(at 2.050034 31.874968 270)
			(size 0.519938 1.4986)
			(layers "F.Cu" "F.Mask" "F.Paste")
			(net "GND")
		)
		(pad "252" smd rect
			(at 2.050034 32.725106 270)
			(size 0.519938 1.4986)
			(layers "F.Cu" "F.Mask" "F.Paste")
			(net "M_G_CPU0_SB_DQ<6>")
		)
		(pad "253" smd rect
			(at 2.050034 33.57499 270)
			(size 0.519938 1.4986)
			(layers "F.Cu" "F.Mask" "F.Paste")
			(net "GND")
		)
		(pad "254" smd rect
			(at 2.050034 34.425128 270)
			(size 0.519938 1.4986)
			(layers "F.Cu" "F.Mask" "F.Paste")
			(net "M_G_CPU0_SB_DQ<7>")
		)
		(pad "255" smd rect
			(at 2.050034 35.275012 270)
			(size 0.519938 1.4986)
			(layers "F.Cu" "F.Mask" "F.Paste")
			(net "GND")
		)
		(pad "256" smd rect
			(at 2.050034 36.124896 270)
			(size 0.519938 1.4986)
			(layers "F.Cu" "F.Mask" "F.Paste")
			(net "M_G_CPU0_SB_DQ<10>")
		)
		(pad "257" smd rect
			(at 2.050034 36.975034 270)
			(size 0.519938 1.4986)
			(layers "F.Cu" "F.Mask" "F.Paste")
			(net "GND")
		)
		(pad "258" smd rect
			(at 2.050034 37.824918 270)
			(size 0.519938 1.4986)
			(layers "F.Cu" "F.Mask" "F.Paste")
			(net "M_G_CPU0_SB_DQ<11>")
		)
		(pad "259" smd rect
			(at 2.050034 38.675056 270)
			(size 0.519938 1.4986)
			(layers "F.Cu" "F.Mask" "F.Paste")
			(net "GND")
		)
		(pad "260" smd rect
			(at 2.050034 39.52494 270)
			(size 0.519938 1.4986)
			(layers "F.Cu" "F.Mask" "F.Paste")
			(net "M_G_CPU0_SB_DQS_DN<6>")
		)
		(pad "261" smd rect
			(at 2.050034 40.375078 270)
			(size 0.519938 1.4986)
			(layers "F.Cu" "F.Mask" "F.Paste")
			(net "M_G_CPU0_SB_DQS_DP<6>")
		)
		(pad "262" smd rect
			(at 2.050034 41.224962 270)
			(size 0.519938 1.4986)
			(layers "F.Cu" "F.Mask" "F.Paste")
			(net "GND")
		)
		(pad "263" smd rect
			(at 2.050034 42.0751 270)
			(size 0.519938 1.4986)
			(layers "F.Cu" "F.Mask" "F.Paste")
			(net "M_G_CPU0_SB_DQ<14>")
		)
		(pad "264" smd rect
			(at 2.050034 42.924984 270)
			(size 0.519938 1.4986)
			(layers "F.Cu" "F.Mask" "F.Paste")
			(net "GND")
		)
		(pad "265" smd rect
			(at 2.050034 43.775122 270)
			(size 0.519938 1.4986)
			(layers "F.Cu" "F.Mask" "F.Paste")
			(net "M_G_CPU0_SB_DQ<15>")
		)
		(pad "266" smd rect
			(at 2.050034 44.625006 270)
			(size 0.519938 1.4986)
			(layers "F.Cu" "F.Mask" "F.Paste")
			(net "GND")
		)
		(pad "267" smd rect
			(at 2.050034 45.47489 270)
			(size 0.519938 1.4986)
			(layers "F.Cu" "F.Mask" "F.Paste")
			(net "M_G_CPU0_SB_DQ<18>")
		)
		(pad "268" smd rect
			(at 2.050034 46.325028 270)
			(size 0.519938 1.4986)
			(layers "F.Cu" "F.Mask" "F.Paste")
			(net "GND")
		)
		(pad "269" smd rect
			(at 2.050034 47.174912 270)
			(size 0.519938 1.4986)
			(layers "F.Cu" "F.Mask" "F.Paste")
			(net "M_G_CPU0_SB_DQ<19>")
		)
		(pad "270" smd rect
			(at 2.050034 48.02505 270)
			(size 0.519938 1.4986)
			(layers "F.Cu" "F.Mask" "F.Paste")
			(net "GND")
		)
		(pad "271" smd rect
			(at 2.050034 48.874934 270)
			(size 0.519938 1.4986)
			(layers "F.Cu" "F.Mask" "F.Paste")
			(net "M_G_CPU0_SB_DQS_DN<7>")
		)
		(pad "272" smd rect
			(at 2.050034 49.725072 270)
			(size 0.519938 1.4986)
			(layers "F.Cu" "F.Mask" "F.Paste")
			(net "M_G_CPU0_SB_DQS_DP<7>")
		)
		(pad "273" smd rect
			(at 2.050034 50.574956 270)
			(size 0.519938 1.4986)
			(layers "F.Cu" "F.Mask" "F.Paste")
			(net "GND")
		)
		(pad "274" smd rect
			(at 2.050034 51.425094 270)
			(size 0.519938 1.4986)
			(layers "F.Cu" "F.Mask" "F.Paste")
			(net "M_G_CPU0_SB_DQ<22>")
		)
	)
)
